(kicad_pcb
	(version 20260206)
	(generator "pcbnew")
	(generator_version "10.0")
	(general
		(thickness 1.6)
		(legacy_teardrops no)
	)
	(paper "A4")
	(title_block
		(title "Bryce Canyon_F.DPB_16315-1-OCP.brd")
		(comment 1 "Bryce Canyon / footprints 1526-1533 of 2223")
	)
	(layers
		(0 "F.Cu" signal "TOP")
		(4 "In1.Cu" signal "L2GND")
		(6 "In2.Cu" signal "L3")
		(8 "In3.Cu" signal "L4GND")
		(10 "In4.Cu" signal "L5")
		(12 "In5.Cu" signal "L6VCC")
		(14 "In6.Cu" signal "L7VCC")
		(16 "In7.Cu" signal "L8")
		(18 "In8.Cu" signal "L9GND")
		(20 "In9.Cu" signal "L10")
		(22 "In10.Cu" signal "L11GND")
		(2 "B.Cu" signal "BOTTOM")
		(9 "F.Adhes" user "F.Adhesive")
		(11 "B.Adhes" user "B.Adhesive")
		(13 "F.Paste" user "Package Geometry/Pastemask Top")
		(15 "B.Paste" user "Package Geometry/Pastemask Bottom")
		(5 "F.SilkS" user "Ref Des/Silkscreen Top")
		(7 "B.SilkS" user "Ref Des/Silkscreen Bottom")
		(1 "F.Mask" user "Board Geometry/Soldermask Top")
		(3 "B.Mask" user "Board Geometry/Soldermask Bottom")
		(17 "Dwgs.User" user "User.Drawings")
		(19 "Cmts.User" user "User.Comments")
		(21 "Eco1.User" user "User.Eco1")
		(23 "Eco2.User" user "User.Eco2")
		(25 "Edge.Cuts" user "Board Geometry/Outline")
		(27 "Margin" user)
		(31 "F.CrtYd" user "Package Geometry/Place Bound Top")
		(29 "B.CrtYd" user "Package Geometry/Place Bound Bottom")
		(35 "F.Fab" user "Ref Des/Assembly Top")
		(33 "B.Fab" user "Ref Des/Assembly Bottom")
	)
	(footprint ""
		(layer "F.Cu")
		(at 165.776402 -129.286)
		(property "Reference" "R312"
			(at 0 0 0)
			(layer "F.SilkS")
			(hide yes)
			(effects
				(font
					(size 1.27 1.27)
				)
			)
		)
		(property "Value" "91R3F-1-GP"
			(at -0.0254 -2.5146 0)
			(unlocked yes)
			(layer "F.Fab")
			(hide yes)
			(effects
				(font
					(size 1.016 1.016)
					(thickness 0.1524)
				)
			)
		)
		(property "Device Type" "R603H22"
			(at -0.0254 -4.0386 0)
			(unlocked yes)
			(layer "F.Fab")
			(hide yes)
			(effects
				(font
					(size 1.016 1.016)
					(thickness 0.1524)
				)
			)
		)
		(duplicate_pad_numbers_are_jumpers no)
		(fp_line
			(start -0.4826 0)
			(end -0.2032 0)
			(stroke
				(width 0.2032)
				(type default)
			)
			(layer "F.SilkS")
		)
		(fp_line
			(start 0.2032 0)
			(end 0.4826 0)
			(stroke
				(width 0.2032)
				(type default)
			)
			(layer "F.SilkS")
		)
		(fp_rect
			(start -0.5842 1.3335)
			(end 0.5842 -1.3335)
			(stroke
				(width 0)
				(type default)
			)
			(fill no)
			(layer "F.CrtYd")
		)
		(fp_rect
			(start -0.5842 1.3335)
			(end 0.5842 -1.3335)
			(stroke
				(width 0)
				(type default)
			)
			(fill no)
			(layer "F.Fab")
		)
		(pad "1" smd custom
			(at 0 -0.762)
			(size 0.2159 0.2159)
			(layers "F.Cu" "F.Mask" "F.Paste")
			(net "P5V_A_2")
			(options
				(clearance outline)
				(anchor circle)
			)
			(primitives
				(gr_poly
					(pts
						(arc
							(start -0.3302 -0.4318)
							(mid -0.402042 -0.402042)
							(end -0.4318 -0.3302)
						)
						(arc
							(start -0.4318 0.3302)
							(mid -0.402042 0.402042)
							(end -0.3302 0.4318)
						)
						(arc
							(start 0.3302 0.4318)
							(mid 0.402042 0.402042)
							(end 0.4318 0.3302)
						)
						(arc
							(start 0.4318 -0.3302)
							(mid 0.402042 -0.402042)
							(end 0.3302 -0.4318)
						)
					)
					(width 0)
					(fill yes)
				)
			)
		)
		(pad "2" smd custom
			(at 0 0.762)
			(size 0.2159 0.2159)
			(layers "F.Cu" "F.Mask" "F.Paste")
			(net "DRV_ACT_17")
			(options
				(clearance outline)
				(anchor circle)
			)
			(primitives
				(gr_poly
					(pts
						(arc
							(start -0.3302 -0.4318)
							(mid -0.402042 -0.402042)
							(end -0.4318 -0.3302)
						)
						(arc
							(start -0.4318 0.3302)
							(mid -0.402042 0.402042)
							(end -0.3302 0.4318)
						)
						(arc
							(start 0.3302 0.4318)
							(mid 0.402042 0.402042)
							(end 0.4318 0.3302)
						)
						(arc
							(start 0.4318 -0.3302)
							(mid 0.402042 -0.402042)
							(end 0.3302 -0.4318)
						)
					)
					(width 0)
					(fill yes)
				)
			)
		)
	)
	(footprint ""
		(layer "F.Cu")
		(at 268.6558 -230.3018 180)
		(property "Reference" "R91"
			(at 0 0 180)
			(layer "F.SilkS")
			(hide yes)
			(effects
				(font
					(size 1.27 1.27)
				)
			)
		)
		(property "Value" "4K7R2F-GP"
			(at 0.064008 -3.993896 180)
			(unlocked yes)
			(layer "F.Fab")
			(hide yes)
			(effects
				(font
					(size 1.016 1.016)
					(thickness 0.1524)
				)
			)
		)
		(property "Device Type" "R402H16"
			(at 0.064008 -5.517896 180)
			(unlocked yes)
			(layer "F.Fab")
			(hide yes)
			(effects
				(font
					(size 1.016 1.016)
					(thickness 0.1524)
				)
			)
		)
		(duplicate_pad_numbers_are_jumpers no)
		(fp_line
			(start 0.508 -0.9398)
			(end -0.508 -0.9398)
			(stroke
				(width 0.1524)
				(type default)
			)
			(layer "F.SilkS")
		)
		(fp_line
			(start -0.508 -0.9398)
			(end -0.508 0.9398)
			(stroke
				(width 0.1524)
				(type default)
			)
			(layer "F.SilkS")
		)
		(fp_rect
			(start -0.508 0.9398)
			(end 0.508 -0.9398)
			(stroke
				(width 0)
				(type default)
			)
			(fill no)
			(layer "F.CrtYd")
		)
		(fp_rect
			(start -0.508 0.9398)
			(end 0.508 -0.9398)
			(stroke
				(width 0)
				(type default)
			)
			(fill no)
			(layer "F.Fab")
		)
		(pad "1" smd custom
			(at 0 -0.4445 180)
			(size 0.1397 0.1397)
			(layers "F.Cu" "F.Mask" "F.Paste")
			(net "P3V3_STBY_A")
			(options
				(clearance outline)
				(anchor circle)
			)
			(primitives
				(gr_poly
					(pts
						(arc
							(start -0.1778 -0.2794)
							(mid -0.249642 -0.249642)
							(end -0.2794 -0.1778)
						)
						(arc
							(start -0.2794 0.1778)
							(mid -0.249642 0.249642)
							(end -0.1778 0.2794)
						)
						(arc
							(start 0.1778 0.2794)
							(mid 0.249642 0.249642)
							(end 0.2794 0.1778)
						)
						(arc
							(start 0.2794 -0.1778)
							(mid 0.249642 -0.249642)
							(end 0.1778 -0.2794)
						)
					)
					(width 0)
					(fill yes)
				)
			)
		)
		(pad "2" smd custom
			(at 0 0.4445 180)
			(size 0.1397 0.1397)
			(layers "F.Cu" "F.Mask" "F.Paste")
			(net "IO_EXP3_A2")
			(options
				(clearance outline)
				(anchor circle)
			)
			(primitives
				(gr_poly
					(pts
						(arc
							(start -0.1778 -0.2794)
							(mid -0.249642 -0.249642)
							(end -0.2794 -0.1778)
						)
						(arc
							(start -0.2794 0.1778)
							(mid -0.249642 0.249642)
							(end -0.1778 0.2794)
						)
						(arc
							(start 0.1778 0.2794)
							(mid 0.249642 0.249642)
							(end 0.2794 0.1778)
						)
						(arc
							(start 0.2794 -0.1778)
							(mid 0.249642 -0.249642)
							(end 0.1778 -0.2794)
						)
					)
					(width 0)
					(fill yes)
				)
			)
		)
	)
	(footprint ""
		(layer "F.Cu")
		(at 267.197078 -130.124708 90)
		(property "Reference" "TP183"
			(at 0 0 90)
			(layer "F.SilkS")
			(hide yes)
			(effects
				(font
					(size 1.27 1.27)
				)
			)
		)
		(property "Value" "TPAD32-GP"
			(at -0.0508 -1.6764 90)
			(unlocked yes)
			(layer "F.Fab")
			(hide yes)
			(effects
				(font
					(size 1.016 1.016)
					(thickness 0.1524)
				)
			)
		)
		(property "Device Type" "TPAD32"
			(at -0.0508 -3.2004 90)
			(unlocked yes)
			(layer "F.Fab")
			(hide yes)
			(effects
				(font
					(size 1.016 1.016)
					(thickness 0.1524)
				)
			)
		)
		(duplicate_pad_numbers_are_jumpers no)
		(fp_poly
			(pts
				(arc
					(start 0 0.4064)
					(mid 0 -0.4064)
					(end 0 0.4064)
				)
			)
			(stroke
				(width 0)
				(type default)
			)
			(fill no)
			(layer "F.CrtYd")
		)
		(fp_poly
			(pts
				(arc
					(start 0 0.7112)
					(mid 0 -0.7112)
					(end 0 0.7112)
				)
			)
			(stroke
				(width 0)
				(type default)
			)
			(fill no)
			(layer "F.Fab")
		)
		(pad "1" smd circle
			(at 0 0 90)
			(size 0.8128 0.8128)
			(layers "F.Cu" "F.Mask" "F.Paste")
			(net "TP_COMP_B_SATA_P0_TX_DP")
		)
	)
	(footprint ""
		(layer "F.Cu")
		(at 272.542 -357.704898 180)
		(property "Reference" "VIA35"
			(at 0 0 180)
			(layer "F.SilkS")
			(hide yes)
			(effects
				(font
					(size 1.27 1.27)
				)
			)
		)
		(property "Value" "100OHM-8L-1D6MM-L18L16-GP"
			(at -3.7211 -4.5085 180)
			(unlocked yes)
			(layer "F.Fab")
			(hide yes)
			(effects
				(font
					(size 1.016 1.016)
					(thickness 0.1524)
				)
			)
		)
		(property "Device Type" "VIA-PCIE-4P-394076"
			(at -3.7211 -6.0325 180)
			(unlocked yes)
			(layer "F.Fab")
			(hide yes)
			(effects
				(font
					(size 1.016 1.016)
					(thickness 0.1524)
				)
			)
		)
		(duplicate_pad_numbers_are_jumpers no)
		(fp_rect
			(start -1.9685 0.381)
			(end 1.9685 -0.381)
			(stroke
				(width 0)
				(type default)
			)
			(fill no)
			(layer "F.CrtYd")
		)
		(fp_rect
			(start -1.9685 0.381)
			(end 1.9685 -0.381)
			(stroke
				(width 0)
				(type default)
			)
			(fill no)
			(layer "F.Fab")
		)
		(pad "1" thru_hole circle
			(at -1.5875 0 180)
			(size 0.508 0.508)
			(drill 0.254)
			(layers "*.Cu" "*.Mask")
			(remove_unused_layers no)
			(net "GND")
			(clearance 0.127)
			(thermal_gap 0.127)
		)
		(pad "2" thru_hole circle
			(at -0.5715 0 180)
			(size 0.508 0.508)
			(drill 0.254)
			(layers "*.Cu" "*.Mask")
			(remove_unused_layers no)
			(net "PHY_SCC_A_TO_DRV_A_1_DP")
			(clearance 0.127)
			(thermal_gap 0.127)
		)
		(pad "3" thru_hole circle
			(at 0.5715 0 180)
			(size 0.508 0.508)
			(drill 0.254)
			(layers "*.Cu" "*.Mask")
			(remove_unused_layers no)
			(net "PHY_SCC_A_TO_DRV_A_1_DN")
			(clearance 0.127)
			(thermal_gap 0.127)
		)
		(pad "4" thru_hole circle
			(at 1.5875 0 180)
			(size 0.508 0.508)
			(drill 0.254)
			(layers "*.Cu" "*.Mask")
			(remove_unused_layers no)
			(net "GND")
			(clearance 0.127)
			(thermal_gap 0.127)
		)
	)
	(footprint ""
		(layer "F.Cu")
		(at 364.798102 -157.585918 180)
		(property "Reference" "R575"
			(at 0 0 180)
			(layer "F.SilkS")
			(hide yes)
			(effects
				(font
					(size 1.27 1.27)
				)
			)
		)
		(property "Value" "1KR2F-3-GP"
			(at 0.064008 -3.993896 180)
			(unlocked yes)
			(layer "F.Fab")
			(hide yes)
			(effects
				(font
					(size 1.016 1.016)
					(thickness 0.1524)
				)
			)
		)
		(property "Device Type" "R402H16"
			(at 0.064008 -5.517896 180)
			(unlocked yes)
			(layer "F.Fab")
			(hide yes)
			(effects
				(font
					(size 1.016 1.016)
					(thickness 0.1524)
				)
			)
		)
		(duplicate_pad_numbers_are_jumpers no)
		(fp_line
			(start 0.508 -0.9398)
			(end -0.508 -0.9398)
			(stroke
				(width 0.1524)
				(type default)
			)
			(layer "F.SilkS")
		)
		(fp_line
			(start -0.508 -0.9398)
			(end -0.508 0.9398)
			(stroke
				(width 0.1524)
				(type default)
			)
			(layer "F.SilkS")
		)
		(fp_rect
			(start -0.508 0.9398)
			(end 0.508 -0.9398)
			(stroke
				(width 0)
				(type default)
			)
			(fill no)
			(layer "F.CrtYd")
		)
		(fp_rect
			(start -0.508 0.9398)
			(end 0.508 -0.9398)
			(stroke
				(width 0)
				(type default)
			)
			(fill no)
			(layer "F.Fab")
		)
		(pad "1" smd custom
			(at 0 -0.4445 180)
			(size 0.1397 0.1397)
			(layers "F.Cu" "F.Mask" "F.Paste")
			(net "P3V3_STBY_A")
			(options
				(clearance outline)
				(anchor circle)
			)
			(primitives
				(gr_poly
					(pts
						(arc
							(start -0.1778 -0.2794)
							(mid -0.249642 -0.249642)
							(end -0.2794 -0.1778)
						)
						(arc
							(start -0.2794 0.1778)
							(mid -0.249642 0.249642)
							(end -0.1778 0.2794)
						)
						(arc
							(start 0.1778 0.2794)
							(mid 0.249642 0.249642)
							(end 0.2794 0.1778)
						)
						(arc
							(start 0.2794 -0.1778)
							(mid 0.249642 -0.249642)
							(end 0.1778 -0.2794)
						)
					)
					(width 0)
					(fill yes)
				)
			)
		)
		(pad "2" smd custom
			(at 0 0.4445 180)
			(size 0.1397 0.1397)
			(layers "F.Cu" "F.Mask" "F.Paste")
			(net "SW_PWR_R_HDD19")
			(options
				(clearance outline)
				(anchor circle)
			)
			(primitives
				(gr_poly
					(pts
						(arc
							(start -0.1778 -0.2794)
							(mid -0.249642 -0.249642)
							(end -0.2794 -0.1778)
						)
						(arc
							(start -0.2794 0.1778)
							(mid -0.249642 0.249642)
							(end -0.1778 0.2794)
						)
						(arc
							(start 0.1778 0.2794)
							(mid 0.249642 0.249642)
							(end 0.2794 0.1778)
						)
						(arc
							(start 0.2794 -0.1778)
							(mid 0.249642 -0.249642)
							(end 0.1778 -0.2794)
						)
					)
					(width 0)
					(fill yes)
				)
			)
		)
	)
	(footprint ""
		(layer "F.Cu")
		(at 463.1309 -160.735518 180)
		(property "Reference" "R650"
			(at 0 0 180)
			(layer "F.SilkS")
			(hide yes)
			(effects
				(font
					(size 1.27 1.27)
				)
			)
		)
		(property "Value" "4K7R2J-2-GP"
			(at 0.064008 -3.993896 180)
			(unlocked yes)
			(layer "F.Fab")
			(hide yes)
			(effects
				(font
					(size 1.016 1.016)
					(thickness 0.1524)
				)
			)
		)
		(property "Device Type" "R402H16"
			(at 0.064008 -5.517896 180)
			(unlocked yes)
			(layer "F.Fab")
			(hide yes)
			(effects
				(font
					(size 1.016 1.016)
					(thickness 0.1524)
				)
			)
		)
		(duplicate_pad_numbers_are_jumpers no)
		(fp_line
			(start 0.508 -0.9398)
			(end -0.508 -0.9398)
			(stroke
				(width 0.1524)
				(type default)
			)
			(layer "F.SilkS")
		)
		(fp_line
			(start -0.508 -0.9398)
			(end -0.508 0.9398)
			(stroke
				(width 0.1524)
				(type default)
			)
			(layer "F.SilkS")
		)
		(fp_rect
			(start -0.508 0.9398)
			(end 0.508 -0.9398)
			(stroke
				(width 0)
				(type default)
			)
			(fill no)
			(layer "F.CrtYd")
		)
		(fp_rect
			(start -0.508 0.9398)
			(end 0.508 -0.9398)
			(stroke
				(width 0)
				(type default)
			)
			(fill no)
			(layer "F.Fab")
		)
		(pad "1" smd custom
			(at 0 -0.4445 180)
			(size 0.1397 0.1397)
			(layers "F.Cu" "F.Mask" "F.Paste")
			(net "P12V_A")
			(options
				(clearance outline)
				(anchor circle)
			)
			(primitives
				(gr_poly
					(pts
						(arc
							(start -0.1778 -0.2794)
							(mid -0.249642 -0.249642)
							(end -0.2794 -0.1778)
						)
						(arc
							(start -0.2794 0.1778)
							(mid -0.249642 0.249642)
							(end -0.1778 0.2794)
						)
						(arc
							(start 0.1778 0.2794)
							(mid 0.249642 0.249642)
							(end 0.2794 0.1778)
						)
						(arc
							(start 0.2794 -0.1778)
							(mid 0.249642 -0.249642)
							(end 0.1778 -0.2794)
						)
					)
					(width 0)
					(fill yes)
				)
			)
		)
		(pad "2" smd custom
			(at 0 0.4445 180)
			(size 0.1397 0.1397)
			(layers "F.Cu" "F.Mask" "F.Paste")
			(net "SW_HDD_R22")
			(options
				(clearance outline)
				(anchor circle)
			)
			(primitives
				(gr_poly
					(pts
						(arc
							(start -0.1778 -0.2794)
							(mid -0.249642 -0.249642)
							(end -0.2794 -0.1778)
						)
						(arc
							(start -0.2794 0.1778)
							(mid -0.249642 0.249642)
							(end -0.1778 0.2794)
						)
						(arc
							(start 0.1778 0.2794)
							(mid 0.249642 0.249642)
							(end 0.2794 0.1778)
						)
						(arc
							(start 0.2794 -0.1778)
							(mid 0.249642 -0.249642)
							(end 0.1778 -0.2794)
						)
					)
					(width 0)
					(fill yes)
				)
			)
		)
	)
	(footprint ""
		(layer "F.Cu")
		(at 22.970998 -46.014894 -90)
		(property "Reference" "R690"
			(at 0 0 270)
			(layer "F.SilkS")
			(hide yes)
			(effects
				(font
					(size 1.27 1.27)
				)
			)
		)
		(property "Value" "1KR2F-3-GP"
			(at 0.064008 -3.993896 270)
			(unlocked yes)
			(layer "F.Fab")
			(hide yes)
			(effects
				(font
					(size 1.016 1.016)
					(thickness 0.1524)
				)
			)
		)
		(property "Device Type" "R402H16"
			(at 0.064008 -5.517896 270)
			(unlocked yes)
			(layer "F.Fab")
			(hide yes)
			(effects
				(font
					(size 1.016 1.016)
					(thickness 0.1524)
				)
			)
		)
		(duplicate_pad_numbers_are_jumpers no)
		(fp_line
			(start -0.508 -0.9398)
			(end -0.508 0.9398)
			(stroke
				(width 0.1524)
				(type default)
			)
			(layer "F.SilkS")
		)
		(fp_line
			(start 0.508 -0.9398)
			(end -0.508 -0.9398)
			(stroke
				(width 0.1524)
				(type default)
			)
			(layer "F.SilkS")
		)
		(fp_rect
			(start -0.508 0.9398)
			(end 0.508 -0.9398)
			(stroke
				(width 0)
				(type default)
			)
			(fill no)
			(layer "F.CrtYd")
		)
		(fp_rect
			(start -0.508 0.9398)
			(end 0.508 -0.9398)
			(stroke
				(width 0)
				(type default)
			)
			(fill no)
			(layer "F.Fab")
		)
		(pad "1" smd custom
			(at 0 -0.4445 270)
			(size 0.1397 0.1397)
			(layers "F.Cu" "F.Mask" "F.Paste")
			(net "P3V3_STBY_A")
			(options
				(clearance outline)
				(anchor circle)
			)
			(primitives
				(gr_poly
					(pts
						(arc
							(start -0.1778 -0.2794)
							(mid -0.249642 -0.249642)
							(end -0.2794 -0.1778)
						)
						(arc
							(start -0.2794 0.1778)
							(mid -0.249642 0.249642)
							(end -0.1778 0.2794)
						)
						(arc
							(start 0.1778 0.2794)
							(mid 0.249642 0.249642)
							(end 0.2794 0.1778)
						)
						(arc
							(start 0.2794 -0.1778)
							(mid 0.249642 -0.249642)
							(end 0.1778 -0.2794)
						)
					)
					(width 0)
					(fill yes)
				)
			)
		)
		(pad "2" smd custom
			(at 0 0.4445 270)
			(size 0.1397 0.1397)
			(layers "F.Cu" "F.Mask" "F.Paste")
			(net "SW_PWR_R_HDD24")
			(options
				(clearance outline)
				(anchor circle)
			)
			(primitives
				(gr_poly
					(pts
						(arc
							(start -0.1778 -0.2794)
							(mid -0.249642 -0.249642)
							(end -0.2794 -0.1778)
						)
						(arc
							(start -0.2794 0.1778)
							(mid -0.249642 0.249642)
							(end -0.1778 0.2794)
						)
						(arc
							(start 0.1778 0.2794)
							(mid 0.249642 0.249642)
							(end 0.2794 0.1778)
						)
						(arc
							(start 0.2794 -0.1778)
							(mid 0.249642 -0.249642)
							(end 0.1778 -0.2794)
						)
					)
					(width 0)
					(fill yes)
				)
			)
		)
	)
	(footprint ""
		(layer "F.Cu")
		(at 150.136098 -71.287894)
		(property "Reference" "C409"
			(at 0 0 0)
			(layer "F.SilkS")
			(hide yes)
			(effects
				(font
					(size 1.27 1.27)
				)
			)
		)
		(property "Value" "SC4D7U25V5KX-1-GP"
			(at -0.0762 -6.1214 0)
			(unlocked yes)
			(layer "F.Fab")
			(hide yes)
			(effects
				(font
					(size 1.016 1.016)
					(thickness 0.1524)
				)
			)
		)
		(property "Device Type" "C805H58"
			(at -0.0762 -8.1534 0)
			(unlocked yes)
			(layer "F.Fab")
			(hide yes)
			(effects
				(font
					(size 1.016 1.016)
					(thickness 0.1524)
				)
			)
		)
		(duplicate_pad_numbers_are_jumpers no)
		(fp_line
			(start 0.635 0)
			(end -0.635 0)
			(stroke
				(width 0.508)
				(type default)
			)
			(layer "F.SilkS")
		)
		(fp_rect
			(start -0.9652 1.778)
			(end 0.9652 -1.778)
			(stroke
				(width 0)
				(type default)
			)
			(fill no)
			(layer "F.CrtYd")
		)
		(fp_poly
			(pts
				(xy -0.9652 -1.778) (xy 0.9652 -1.778) (xy 0.9652 1.778) (xy -0.9652 1.778)
			)
			(stroke
				(width 0)
				(type default)
			)
			(fill no)
			(layer "F.Fab")
		)
		(pad "1" smd rect
			(at 0 -0.9652)
			(size 1.397 1.143)
			(layers "F.Cu" "F.Mask" "F.Paste")
			(net "P12V_HDD28")
		)
		(pad "2" smd rect
			(at 0 0.9652)
			(size 1.397 1.143)
			(layers "F.Cu" "F.Mask" "F.Paste")
			(net "GND")
		)
	)
)
